# BASEBOARD_FAB2 (Tioga Pass) — schematic netlist excerpt (pin names and nets, part order shuffled) for the footprints in the layout excerpt that follows; sources: Cadence DE-HDL packaged netlist, KiCad conversion of Wiwynn_Tioga_Pass_MB.brd

C2P10  CAP  22UF 16V 10% X6S  pkg 1206LF  page 188 : A = P12V_STBY ; B = GND

U25W18  TTL1G08  NC7SZ08 IC  pkg SOTLF  page 255
  A(0)  = XDP_PRESENT_N
  B(0)  = BMC_JTAG_SEL
  Y(0)  = BMC_JTAG_SEL_BUF

C2N4  CAP_A  1.0UF 6.3V 10% X6S  pkg 0402V  page 132 : A = PVNN_PCH_STBY ; B = GND

(kicad_pcb
	(version 20260206)
	(generator "pcbnew")
	(generator_version "10.0")
	(general
		(thickness 1.6)
		(legacy_teardrops no)
	)
	(paper "A4")
	(title_block
		(title "Wiwynn_Tioga_Pass_MB.brd")
		(comment 1 "Tioga Pass / footprints 3803-3805 of 4770")
	)
	(layers
		(0 "F.Cu" signal "TOP")
		(4 "In1.Cu" signal "L2GND")
		(6 "In2.Cu" signal "L3")
		(8 "In3.Cu" signal "L4GND")
		(10 "In4.Cu" signal "L5")
		(12 "In5.Cu" signal "L6GND")
		(14 "In6.Cu" signal "L7VCC")
		(16 "In7.Cu" signal "L8VCC")
		(18 "In8.Cu" signal "L9GND")
		(20 "In9.Cu" signal "L10")
		(22 "In10.Cu" signal "L11GND")
		(24 "In11.Cu" signal "L12")
		(26 "In12.Cu" signal "L13GND")
		(2 "B.Cu" signal "BOTTOM")
		(9 "F.Adhes" user "F.Adhesive")
		(11 "B.Adhes" user "B.Adhesive")
		(13 "F.Paste" user "Package Geometry/Pastemask Top")
		(15 "B.Paste" user "Package Geometry/Pastemask Bottom")
		(5 "F.SilkS" user "Ref Des/Silkscreen Top")
		(7 "B.SilkS" user "Ref Des/Silkscreen Bottom")
		(1 "F.Mask" user "Board Geometry/Soldermask Top")
		(3 "B.Mask" user "Board Geometry/Soldermask Bottom")
		(17 "Dwgs.User" user "User.Drawings")
		(19 "Cmts.User" user "User.Comments")
		(21 "Eco1.User" user "User.Eco1")
		(23 "Eco2.User" user "User.Eco2")
		(25 "Edge.Cuts" user "Board Geometry/Outline")
		(27 "Margin" user)
		(31 "F.CrtYd" user "Package Geometry/Place Bound Top")
		(29 "B.CrtYd" user "Package Geometry/Place Bound Bottom")
		(35 "F.Fab" user "Ref Des/Assembly Top")
		(33 "B.Fab" user "Ref Des/Assembly Bottom")
	)
	(footprint ""
		(layer "B.Cu")
		(at 445.5922 -155.8544 180)
		(property "Reference" "U25W18"
			(at 0.14986 2.621788 180)
			(unlocked yes)
			(layer "B.SilkS")
			(effects
				(font
					(size 1.27 0.964946)
					(thickness 0.000001)
				)
				(justify left mirror)
			)
		)
		(property "Value" ""
			(at 0 0 0)
			(layer "B.Fab")
			(effects
				(font
					(size 1.27 1.27)
				)
				(justify mirror)
			)
		)
		(duplicate_pad_numbers_are_jumpers no)
		(fp_circle
			(center 0.4699 -0.8382)
			(end 0.3429 -0.8382)
			(stroke
				(width 0.254)
				(type default)
			)
			(fill no)
			(layer "B.SilkS")
		)
		(fp_poly
			(pts
				(xy -0.21463 -0.450088) (xy -1.56337 -0.450088) (xy -1.56337 1.75006) (xy -0.21463 1.75006)
			)
			(stroke
				(width 0)
				(type default)
			)
			(fill no)
			(layer "B.CrtYd")
		)
		(fp_line
			(start -0.21463 1.75006)
			(end -0.21463 -0.450088)
			(stroke
				(width 0.1)
				(type default)
			)
			(layer "B.Fab")
		)
		(fp_line
			(start -0.21463 -0.450088)
			(end -1.56337 -0.450088)
			(stroke
				(width 0.1)
				(type default)
			)
			(layer "B.Fab")
		)
		(fp_line
			(start -1.56337 1.75006)
			(end -0.21463 1.75006)
			(stroke
				(width 0.1)
				(type default)
			)
			(layer "B.Fab")
		)
		(fp_line
			(start -1.56337 -0.450088)
			(end -1.56337 1.75006)
			(stroke
				(width 0.1)
				(type default)
			)
			(layer "B.Fab")
		)
		(fp_circle
			(center 0.4699 -0.8382)
			(end 0.3429 -0.8382)
			(stroke
				(width 0.254)
				(type default)
			)
			(fill no)
			(layer "B.Fab")
		)
		(pad "1" smd rect
			(at 0 0)
			(size 1.016 0.381)
			(layers "B.Cu" "B.Mask" "B.Paste")
			(net "XDP_PRESENT_N")
		)
		(pad "2" smd rect
			(at 0 0.649986)
			(size 1.016 0.381)
			(layers "B.Cu" "B.Mask" "B.Paste")
			(net "BMC_JTAG_SEL")
		)
		(pad "3" smd rect
			(at 0 1.299972)
			(size 1.016 0.381)
			(layers "B.Cu" "B.Mask" "B.Paste")
			(net "GND")
		)
		(pad "4" smd rect
			(at -1.778 1.299972)
			(size 1.016 0.381)
			(layers "B.Cu" "B.Mask" "B.Paste")
			(net "BMC_JTAG_SEL_BUF")
		)
		(pad "5" smd rect
			(at -1.778 0)
			(size 1.016 0.381)
			(layers "B.Cu" "B.Mask" "B.Paste")
			(net "P3V3_STBY")
		)
	)
	(footprint ""
		(layer "B.Cu")
		(at 441.7187 -64.9986 -90)
		(property "Reference" "C2P10"
			(at 0 0 90)
			(layer "B.SilkS")
			(hide yes)
			(effects
				(font
					(size 1.27 1.27)
				)
				(justify mirror)
			)
		)
		(property "Value" ""
			(at 0 0 90)
			(layer "B.Fab")
			(effects
				(font
					(size 1.27 1.27)
				)
				(justify mirror)
			)
		)
		(duplicate_pad_numbers_are_jumpers no)
		(fp_line
			(start -0.9017 1.953768)
			(end -0.9017 0.824484)
			(stroke
				(width 0.1524)
				(type default)
			)
			(layer "B.SilkS")
		)
		(fp_line
			(start 0.9017 1.953006)
			(end 0.9017 0.823976)
			(stroke
				(width 0.1524)
				(type default)
			)
			(layer "B.SilkS")
		)
		(fp_poly
			(pts
				(xy 0.9017 -0.3048) (xy -0.9017 -0.3048) (xy -0.9017 3.0988) (xy 0.9017 3.0988)
			)
			(stroke
				(width 0)
				(type default)
			)
			(fill no)
			(layer "B.CrtYd")
		)
		(fp_line
			(start -0.9017 3.0988)
			(end -0.9017 -0.3048)
			(stroke
				(width 0.1)
				(type default)
			)
			(layer "B.Fab")
		)
		(fp_line
			(start 0.9017 3.0988)
			(end -0.9017 3.0988)
			(stroke
				(width 0.1)
				(type default)
			)
			(layer "B.Fab")
		)
		(fp_line
			(start -0.9017 -0.3048)
			(end 0.9017 -0.3048)
			(stroke
				(width 0.1)
				(type default)
			)
			(layer "B.Fab")
		)
		(fp_line
			(start 0.9017 -0.3048)
			(end 0.9017 3.0988)
			(stroke
				(width 0.1)
				(type default)
			)
			(layer "B.Fab")
		)
		(pad "1" smd rect
			(at 0 0 90)
			(size 1.524 1.016)
			(layers "B.Cu" "B.Mask" "B.Paste")
			(net "P12V_STBY")
		)
		(pad "2" smd rect
			(at 0 2.794 90)
			(size 1.524 1.016)
			(layers "B.Cu" "B.Mask" "B.Paste")
			(net "GND")
		)
		(zone
			(layer "B.Cu")
			(hatch none 0.5)
			(connect_pads
				(clearance 0)
			)
			(min_thickness 0.25)
			(keepout
				(tracks allowed)
				(vias not_allowed)
				(pads allowed)
				(copperpour not_allowed)
				(footprints allowed)
			)
			(placement
				(enabled no)
				(sheetname "")
			)
			(fill
				(thermal_gap 0.5)
				(thermal_bridge_width 0.5)
				(island_removal_mode 0)
			)
			(polygon
				(pts
					(xy 441.2107 -65.7606) (xy 439.4327 -65.7606) (xy 439.4327 -64.2366) (xy 441.2107 -64.2366)
				)
			)
		)
	)
	(footprint ""
		(layer "B.Cu")
		(at 389.33755 -111.05515 180)
		(property "Reference" "C2N4"
			(at 0 0 0)
			(layer "B.SilkS")
			(hide yes)
			(effects
				(font
					(size 1.27 1.27)
				)
				(justify mirror)
			)
		)
		(property "Value" ""
			(at 0 0 0)
			(layer "B.Fab")
			(effects
				(font
					(size 1.27 1.27)
				)
				(justify mirror)
			)
		)
		(duplicate_pad_numbers_are_jumpers no)
		(fp_rect
			(start 0.2794 0.9144)
			(end -0.2794 -0.1143)
			(stroke
				(width 0)
				(type default)
			)
			(fill no)
			(layer "B.CrtYd")
		)
		(fp_line
			(start 0.2794 0.9144)
			(end 0.2794 -0.1143)
			(stroke
				(width 0.1)
				(type default)
			)
			(layer "B.Fab")
		)
		(fp_line
			(start 0.2794 -0.1143)
			(end -0.2794 -0.1143)
			(stroke
				(width 0.1)
				(type default)
			)
			(layer "B.Fab")
		)
		(fp_line
			(start -0.2794 0.9144)
			(end 0.2794 0.9144)
			(stroke
				(width 0.1)
				(type default)
			)
			(layer "B.Fab")
		)
		(fp_line
			(start -0.2794 -0.1143)
			(end -0.2794 0.9144)
			(stroke
				(width 0.1)
				(type default)
			)
			(layer "B.Fab")
		)
		(pad "1" smd custom
			(at 0 0 90)
			(size 0.10414 0.10414)
			(layers "B.Cu" "B.Mask" "B.Paste")
			(net "PVNN_PCH_STBY")
			(options
				(clearance outline)
				(anchor circle)
			)
			(primitives
				(gr_poly
					(pts
						(xy -0.20828 -0.08636) (xy -0.20828 0.08636) (xy -0.08636 0.20828) (xy 0.086614 0.20828) (xy 0.20828 0.086614)
						(xy 0.20828 -0.08636) (xy 0.08636 -0.20828) (xy -0.08636 -0.20828)
					)
					(width 0)
					(fill yes)
				)
			)
		)
		(pad "2" smd custom
			(at 0 0.8001 90)
			(size 0.10414 0.10414)
			(layers "B.Cu" "B.Mask" "B.Paste")
			(net "GND")
			(options
				(clearance outline)
				(anchor circle)
			)
			(primitives
				(gr_poly
					(pts
						(xy -0.20828 -0.08636) (xy -0.20828 0.08636) (xy -0.08636 0.20828) (xy 0.086614 0.20828) (xy 0.20828 0.086614)
						(xy 0.20828 -0.08636) (xy 0.08636 -0.20828) (xy -0.08636 -0.20828)
					)
					(width 0)
					(fill yes)
				)
			)
		)
		(zone
			(layer "B.Cu")
			(hatch none 0.5)
			(connect_pads
				(clearance 0)
			)
			(min_thickness 0.25)
			(keepout
				(tracks allowed)
				(vias not_allowed)
				(pads allowed)
				(copperpour not_allowed)
				(footprints allowed)
			)
			(placement
				(enabled no)
				(sheetname "")
			)
			(fill
				(thermal_gap 0.5)
				(thermal_bridge_width 0.5)
				(island_removal_mode 0)
			)
			(polygon
				(pts
					(xy 389.24992 -111.2647) (xy 389.24992 -111.6457) (xy 389.42518 -111.6457) (xy 389.425434 -111.2647)
				)
			)
		)
		(zone
			(layer "B.Cu")
			(hatch none 0.5)
			(connect_pads
				(clearance 0)
			)
			(min_thickness 0.25)
			(keepout
				(tracks not_allowed)
				(vias allowed)
				(pads allowed)
				(copperpour not_allowed)
				(footprints allowed)
			)
			(placement
				(enabled no)
				(sheetname "")
			)
			(fill
				(thermal_gap 0.5)
				(thermal_bridge_width 0.5)
				(island_removal_mode 0)
			)
			(polygon
				(pts
					(xy 389.24992 -111.2647) (xy 389.24992 -111.6457) (xy 389.42518 -111.6457) (xy 389.425434 -111.2647)
				)
			)
		)
	)
)
